(kicad_pcb
	(version 20221018)
	(generator pcbnew)
	(general
    (thickness 1.518)
  )
	(paper "A4")
	(title_block
    (title "Kria K26 Devboard")
    (date "2024-03-26")
    (rev "1.2.5")
    (comment 1 "www.antmicro.com")
    (comment 2 "Antmicro Ltd.")
		(comment 9 "footprints 161-167 of 660")
	)
	(layers
    (0 "F.Cu" mixed)
    (1 "In1.Cu" power)
    (2 "In2.Cu" mixed)
    (3 "In3.Cu" power)
    (4 "In4.Cu" mixed)
    (5 "In5.Cu" power)
    (6 "In6.Cu" mixed)
    (31 "B.Cu" power)
    (32 "B.Adhes" user "B.Adhesive")
    (33 "F.Adhes" user "F.Adhesive")
    (34 "B.Paste" user)
    (35 "F.Paste" user)
    (36 "B.SilkS" user "B.Silkscreen")
    (37 "F.SilkS" user "F.Silkscreen")
    (38 "B.Mask" user)
    (39 "F.Mask" user)
    (40 "Dwgs.User" user "User.Drawings")
    (41 "Cmts.User" user "User.Comments")
    (42 "Eco1.User" user "User.Eco1")
    (43 "Eco2.User" user "User.Eco2")
    (44 "Edge.Cuts" user)
    (45 "Margin" user)
    (46 "B.CrtYd" user "B.Courtyard")
    (47 "F.CrtYd" user "F.Courtyard")
    (48 "B.Fab" user)
    (49 "F.Fab" user)
  )
	(footprint "kria-k26-devboard-footprints:VSSOP-8-1EP_3x3x1.1mm_P0.65mm" (layer "F.Cu")
    (at 140.165 73.25 180)
    (property "Author" "Antmicro")
    (property "License" "Apache-2.0")
    (property "MPN" "TPS2066TDGNRQ1")
    (property "Manufacturer" "Texas Instruments")
    (property "Sheetfile" "usb.kicad_sch")
    (property "Sheetname" "USB")
    (property "ki_description" "Power switch")
    (property "ki_keywords" "IC")
    (attr smd)
    (fp_text reference "U16" (at 1.105 -2.55 180) (layer "F.SilkS")
        (effects (font (size 0.7 0.7) (thickness 0.15)) (justify left bottom))
    )
    (fp_text value "TPS2066TDGNRQ1" (at 0 2.8 180) (layer "F.Fab") hide
        (effects (font (size 0.7 0.7) (thickness 0.15)) (justify left bottom))
    )
    (fp_text user "Author: Antmicro" (at -0.301 6.336 180) (layer "F.Fab") hide
        (effects (font (size 0.7 0.7) (thickness 0.15)) (justify left bottom))
    )
    (fp_text user "License: Apache-2.0" (at -0.301 7.336 180) (layer "F.Fab") hide
        (effects (font (size 0.7 0.7) (thickness 0.15)) (justify left bottom))
    )
    (fp_text user "${REFERENCE}" (at 0 0.4 180) (layer "F.Fab") hide
        (effects (font (size 0.7 0.7) (thickness 0.15)) (justify bottom))
    )
    (fp_poly
      (pts
        (xy -0.435 -0.511)
        (xy 0.436 -0.511)
        (xy 0.436 0.514)
        (xy -0.435 0.514)
      )

      (stroke (width 0.01) (type solid)) (fill solid) (layer "F.Paste"))
    (fp_line (start -1.55 1.55) (end 1.552 1.55)
      (stroke (width 0.15) (type solid)) (layer "F.SilkS"))
    (fp_line (start -1.5 -1.548) (end 1.552 -1.55)
      (stroke (width 0.15) (type solid)) (layer "F.SilkS"))
    (fp_circle (center -1.8 -1.4) (end -1.75 -1.35)
      (stroke (width 0.15) (type solid)) (fill solid) (layer "F.SilkS"))
    (fp_rect (start -2.95 -1.75) (end 2.95 1.75)
      (stroke (width 0.05) (type solid)) (fill none) (layer "F.CrtYd"))
    (fp_line (start -1.55 -0.948) (end -1.55 1.55)
      (stroke (width 0.15) (type solid)) (layer "F.Fab"))
    (fp_line (start -1.55 -0.948) (end -0.949 -1.55)
      (stroke (width 0.15) (type solid)) (layer "F.Fab"))
    (fp_line (start -1.55 1.55) (end 1.552 1.55)
      (stroke (width 0.15) (type solid)) (layer "F.Fab"))
    (fp_line (start -0.949 -1.55) (end 1.552 -1.55)
      (stroke (width 0.15) (type solid)) (layer "F.Fab"))
    (fp_line (start 1.552 -1.55) (end 1.552 1.55)
      (stroke (width 0.15) (type solid)) (layer "F.Fab"))
    (pad "1" smd roundrect (at -2.148 -0.973 180) (size 1.47 0.5) (layers "F.Cu" "F.Paste" "F.Mask") (roundrect_rratio 0.25)
      (net 1 "GND") (pinfunction "GND") (pintype "power_in"))
    (pad "2" smd roundrect (at -2.148 -0.324 180) (size 1.47 0.5) (layers "F.Cu" "F.Paste" "F.Mask") (roundrect_rratio 0.25)
      (net 306 "USB_5V") (pinfunction "IN") (pintype "power_in"))
    (pad "3" smd roundrect (at -2.148 0.327 180) (size 1.47 0.5) (layers "F.Cu" "F.Paste" "F.Mask") (roundrect_rratio 0.25)
      (net 302 "/USB/USB_PRT_CTL1") (pinfunction "EN1") (pintype "input"))
    (pad "4" smd roundrect (at -2.148 0.976 180) (size 1.47 0.5) (layers "F.Cu" "F.Paste" "F.Mask") (roundrect_rratio 0.25)
      (net 303 "/USB/USB_PRT_CTL2") (pinfunction "EN2") (pintype "input"))
    (pad "5" smd roundrect (at 2.151 0.976 180) (size 1.47 0.5) (layers "F.Cu" "F.Paste" "F.Mask") (roundrect_rratio 0.25)
      (net 303 "/USB/USB_PRT_CTL2") (pinfunction "~{OC2}") (pintype "output"))
    (pad "6" smd roundrect (at 2.151 0.327 180) (size 1.47 0.5) (layers "F.Cu" "F.Paste" "F.Mask") (roundrect_rratio 0.25)
      (net 85 "/USB/USB2_VBUS") (pinfunction "OUT2") (pintype "output"))
    (pad "7" smd roundrect (at 2.151 -0.324 180) (size 1.47 0.5) (layers "F.Cu" "F.Paste" "F.Mask") (roundrect_rratio 0.25)
      (net 64 "/USB/USB1_VBUS") (pinfunction "OUT1") (pintype "output"))
    (pad "8" smd roundrect (at 2.151 -0.973 180) (size 1.47 0.5) (layers "F.Cu" "F.Paste" "F.Mask") (roundrect_rratio 0.25)
      (net 302 "/USB/USB_PRT_CTL1") (pinfunction "~{OC1}") (pintype "output"))
    (pad "9" smd rect (at 0 0 180) (size 1.746 2.05) (layers "F.Cu" "F.Mask")
      (net 1 "GND") (pinfunction "EP") (pintype "passive"))
  )
	(footprint "kria-k26-devboard-footprints:VSSOP-8-1EP_3x3x1.1mm_P0.65mm" (layer "F.Cu")
    (at 120.32 74.1 180)
    (property "Author" "Antmicro")
    (property "License" "Apache-2.0")
    (property "MPN" "TPS2066TDGNRQ1")
    (property "Manufacturer" "Texas Instruments")
    (property "Sheetfile" "usb.kicad_sch")
    (property "Sheetname" "USB")
    (property "ki_description" "Power switch")
    (property "ki_keywords" "IC")
    (attr smd)
    (fp_text reference "U18" (at 1.38 1.78 180) (layer "F.SilkS")
        (effects (font (size 0.7 0.7) (thickness 0.15)) (justify left bottom))
    )
    (fp_text value "TPS2066TDGNRQ1" (at 0 2.8 180) (layer "F.Fab") hide
        (effects (font (size 0.7 0.7) (thickness 0.15)) (justify left bottom))
    )
    (fp_text user "${REFERENCE}" (at 0 0.4 180) (layer "F.Fab") hide
        (effects (font (size 0.7 0.7) (thickness 0.15)) (justify bottom))
    )
    (fp_text user "Author: Antmicro" (at -0.301 6.336 180) (layer "F.Fab") hide
        (effects (font (size 0.7 0.7) (thickness 0.15)) (justify left bottom))
    )
    (fp_text user "License: Apache-2.0" (at -0.301 7.336 180) (layer "F.Fab") hide
        (effects (font (size 0.7 0.7) (thickness 0.15)) (justify left bottom))
    )
    (fp_poly
      (pts
        (xy -0.435 -0.511)
        (xy 0.436 -0.511)
        (xy 0.436 0.514)
        (xy -0.435 0.514)
      )

      (stroke (width 0.01) (type solid)) (fill solid) (layer "F.Paste"))
    (fp_line (start -1.55 1.55) (end 1.552 1.55)
      (stroke (width 0.15) (type solid)) (layer "F.SilkS"))
    (fp_line (start -1.5 -1.548) (end 1.552 -1.55)
      (stroke (width 0.15) (type solid)) (layer "F.SilkS"))
    (fp_circle (center -1.8 -1.4) (end -1.75 -1.35)
      (stroke (width 0.15) (type solid)) (fill solid) (layer "F.SilkS"))
    (fp_rect (start -2.95 -1.75) (end 2.95 1.75)
      (stroke (width 0.05) (type solid)) (fill none) (layer "F.CrtYd"))
    (fp_line (start -1.55 -0.948) (end -1.55 1.55)
      (stroke (width 0.15) (type solid)) (layer "F.Fab"))
    (fp_line (start -1.55 -0.948) (end -0.949 -1.55)
      (stroke (width 0.15) (type solid)) (layer "F.Fab"))
    (fp_line (start -1.55 1.55) (end 1.552 1.55)
      (stroke (width 0.15) (type solid)) (layer "F.Fab"))
    (fp_line (start -0.949 -1.55) (end 1.552 -1.55)
      (stroke (width 0.15) (type solid)) (layer "F.Fab"))
    (fp_line (start 1.552 -1.55) (end 1.552 1.55)
      (stroke (width 0.15) (type solid)) (layer "F.Fab"))
    (pad "1" smd roundrect (at -2.148 -0.973 180) (size 1.47 0.5) (layers "F.Cu" "F.Paste" "F.Mask") (roundrect_rratio 0.25)
      (net 1 "GND") (pinfunction "GND") (pintype "power_in"))
    (pad "2" smd roundrect (at -2.148 -0.324 180) (size 1.47 0.5) (layers "F.Cu" "F.Paste" "F.Mask") (roundrect_rratio 0.25)
      (net 306 "USB_5V") (pinfunction "IN") (pintype "power_in"))
    (pad "3" smd roundrect (at -2.148 0.327 180) (size 1.47 0.5) (layers "F.Cu" "F.Paste" "F.Mask") (roundrect_rratio 0.25)
      (net 304 "/USB/USB_PRT_CTL3") (pinfunction "EN1") (pintype "input"))
    (pad "4" smd roundrect (at -2.148 0.976 180) (size 1.47 0.5) (layers "F.Cu" "F.Paste" "F.Mask") (roundrect_rratio 0.25)
      (net 305 "/USB/USB_PRT_CTL4") (pinfunction "EN2") (pintype "input"))
    (pad "5" smd roundrect (at 2.151 0.976 180) (size 1.47 0.5) (layers "F.Cu" "F.Paste" "F.Mask") (roundrect_rratio 0.25)
      (net 305 "/USB/USB_PRT_CTL4") (pinfunction "~{OC2}") (pintype "output"))
    (pad "6" smd roundrect (at 2.151 0.327 180) (size 1.47 0.5) (layers "F.Cu" "F.Paste" "F.Mask") (roundrect_rratio 0.25)
      (net 87 "/USB/USB4_VBUS") (pinfunction "OUT2") (pintype "output"))
    (pad "7" smd roundrect (at 2.151 -0.324 180) (size 1.47 0.5) (layers "F.Cu" "F.Paste" "F.Mask") (roundrect_rratio 0.25)
      (net 86 "/USB/USB3_VBUS") (pinfunction "OUT1") (pintype "output"))
    (pad "8" smd roundrect (at 2.151 -0.973 180) (size 1.47 0.5) (layers "F.Cu" "F.Paste" "F.Mask") (roundrect_rratio 0.25)
      (net 304 "/USB/USB_PRT_CTL3") (pinfunction "~{OC1}") (pintype "output"))
    (pad "9" smd rect (at 0 0 180) (size 1.746 2.05) (layers "F.Cu" "F.Mask")
      (net 1 "GND") (pinfunction "EP") (pintype "passive"))
  )
	(footprint "kria-k26-devboard-footprints:Oscillator_SMD_ECS_2016MV_2x1.6x0.85mm" (layer "F.Cu")
    (at 127.042501 97.4475 -90)
    (property "Author" "Antmicro")
    (property "License" "Apache-2.0")
    (property "MPN" "ECS-2016MV-240-CN-TR")
    (property "Manufacturer" "ECS Inc. International")
    (property "Sheetfile" "usb.kicad_sch")
    (property "Sheetname" "USB")
    (property "Val" "24 MHz")
    (property "ki_description" "Oscillator, 24 MHz XO (Standard) CMOS 1.6V ~ 3.6V Enable/Disable 4-SMD, No Lead")
    (property "ki_keywords" "OSCILLATOR")
    (attr smd)
    (fp_text reference "Y5" (at 1.4725 -1.217499 180) (layer "F.SilkS")
        (effects (font (size 0.7 0.7) (thickness 0.15)) (justify left bottom))
    )
    (fp_text value "Oscillator_24MHz_ESC_2016MV" (at 0 2.2 -90) (layer "F.Fab") hide
        (effects (font (size 0.7 0.7) (thickness 0.15)) (justify left bottom))
    )
    (fp_text user "License: Apache-2.0" (at -1.05 5.8 -90) (layer "F.Fab") hide
        (effects (font (size 0.7 0.7) (thickness 0.15)) (justify left bottom))
    )
    (fp_text user "Author: Antmicro" (at -1.05 4.6 -90) (layer "F.Fab") hide
        (effects (font (size 0.7 0.7) (thickness 0.15)) (justify left bottom))
    )
    (fp_text user "${REFERENCE}" (at -1.05 3.4 -90) (layer "F.Fab") hide
        (effects (font (size 0.7 0.7) (thickness 0.15)) (justify left bottom))
    )
    (fp_line (start -0.95 0.4) (end -0.95 -0.4)
      (stroke (width 0.15) (type solid)) (layer "F.SilkS"))
    (fp_line (start -0.4 -1.15) (end 0.4 -1.15)
      (stroke (width 0.15) (type solid)) (layer "F.SilkS"))
    (fp_line (start -0.4 1.15) (end 0.4 1.15)
      (stroke (width 0.15) (type solid)) (layer "F.SilkS"))
    (fp_line (start 0.95 0.4) (end 0.95 -0.4)
      (stroke (width 0.15) (type solid)) (layer "F.SilkS"))
    (fp_circle (center -0.95 -1.15) (end -0.9 -1.15)
      (stroke (width 0.15) (type solid)) (fill solid) (layer "F.SilkS"))
    (fp_rect (start -1.05 -1.25) (end 1.05 1.24)
      (stroke (width 0.05) (type solid)) (fill none) (layer "F.CrtYd"))
    (fp_rect (start -0.85 -1.054) (end 0.852 1.054)
      (stroke (width 0.15) (type solid)) (fill none) (layer "F.Fab"))
    (pad "1" smd rect (at -0.486 -0.637 270) (size 0.6858 0.7874) (layers "F.Cu" "F.Paste" "F.Mask")
      (net 802 "unconnected-(Y5-EN-Pad1)") (pinfunction "EN") (pintype "input+no_connect"))
    (pad "2" smd rect (at -0.486 0.636 270) (size 0.6858 0.7874) (layers "F.Cu" "F.Paste" "F.Mask")
      (net 1 "GND") (pinfunction "GND") (pintype "power_in"))
    (pad "3" smd rect (at 0.487 0.636 270) (size 0.6858 0.7874) (layers "F.Cu" "F.Paste" "F.Mask")
      (net 277 "/USB/USB2_REFCLK") (pinfunction "OUT") (pintype "output"))
    (pad "4" smd rect (at 0.487 -0.637 270) (size 0.6858 0.7874) (layers "F.Cu" "F.Paste" "F.Mask")
      (net 17 "PS_1V8") (pinfunction "VDD") (pintype "power_in"))
  )
	(footprint "kria-k26-devboard-footprints:C_0402_1005Metric" (layer "F.Cu")
    (at 110.675 75.145 90)
    (descr "Capacitor SMD 0402")
    (tags "capacitor SMD 0402")
    (property "Author" "Antmicro")
    (property "Dielectric" "X5R")
    (property "License" "Apache-2.0")
    (property "MPN" "GRM155R61H104KE14D")
    (property "Manufacturer" "Murata")
    (property "Sheetfile" "usb.kicad_sch")
    (property "Sheetname" "USB")
    (property "Val" "100n")
    (property "Voltage" "50V")
    (property "ki_description" " ")
    (attr smd)
    (fp_text reference "C76" (at -3.055 0.385 90) (layer "F.SilkS")
        (effects (font (size 0.7 0.7) (thickness 0.15)) (justify left bottom))
    )
    (fp_text value "C_100n_0402" (at 0 1.4 90) (layer "F.Fab") hide
        (effects (font (size 0.7 0.7) (thickness 0.15)) (justify left bottom))
    )
    (fp_text user "${REFERENCE}" (at -0.932 3.168 90) (layer "F.Fab") hide
        (effects (font (size 0.7 0.7) (thickness 0.15)) (justify left bottom))
    )
    (fp_text user "License: Apache-2.0" (at -0.932 5.17 90) (layer "F.Fab") hide
        (effects (font (size 0.7 0.7) (thickness 0.15)) (justify left bottom))
    )
    (fp_text user "Author: Antmicro" (at -0.932 4.17 90) (layer "F.Fab") hide
        (effects (font (size 0.7 0.7) (thickness 0.15)) (justify left bottom))
    )
    (fp_rect (start -0.94 -0.47) (end 0.94 0.47)
      (stroke (width 0.05) (type solid)) (fill none) (layer "F.CrtYd"))
    (fp_rect (start -0.499 -0.249) (end 0.499 0.249)
      (stroke (width 0.15) (type solid)) (fill none) (layer "F.Fab"))
    (pad "1" smd roundrect (at -0.484 0 90) (size 0.59 0.64) (layers "F.Cu" "F.Paste" "F.Mask") (roundrect_rratio 0.25)
      (net 75 "/USB/USB4_TX_N") (pintype "passive"))
    (pad "2" smd roundrect (at 0.484 0 90) (size 0.59 0.64) (layers "F.Cu" "F.Paste" "F.Mask") (roundrect_rratio 0.25)
      (net 284 "/USB/USB4_TX_C_N") (pintype "passive"))
  )
	(footprint "kria-k26-devboard-footprints:C_0402_1005Metric" (layer "F.Cu")
    (at 123.65 92.91 90)
    (descr "Capacitor SMD 0402")
    (tags "capacitor SMD 0402")
    (property "Author" "Antmicro")
    (property "Dielectric" "X5R")
    (property "License" "Apache-2.0")
    (property "MPN" "GRM155R61H104KE14D")
    (property "Manufacturer" "Murata")
    (property "Sheetfile" "usb.kicad_sch")
    (property "Sheetname" "USB")
    (property "Val" "100n")
    (property "Voltage" "50V")
    (property "ki_description" " ")
    (attr smd)
    (fp_text reference "C53" (at -1.94 -3.25 90) (layer "F.SilkS")
        (effects (font (size 0.7 0.7) (thickness 0.15)) (justify left bottom))
    )
    (fp_text value "C_100n_0402" (at 0 1.4 90) (layer "F.Fab") hide
        (effects (font (size 0.7 0.7) (thickness 0.15)) (justify left bottom))
    )
    (fp_text user "${REFERENCE}" (at -0.932 3.168 90) (layer "F.Fab") hide
        (effects (font (size 0.7 0.7) (thickness 0.15)) (justify left bottom))
    )
    (fp_text user "License: Apache-2.0" (at -0.932 5.17 90) (layer "F.Fab") hide
        (effects (font (size 0.7 0.7) (thickness 0.15)) (justify left bottom))
    )
    (fp_text user "Author: Antmicro" (at -0.932 4.17 90) (layer "F.Fab") hide
        (effects (font (size 0.7 0.7) (thickness 0.15)) (justify left bottom))
    )
    (fp_rect (start -0.94 -0.47) (end 0.94 0.47)
      (stroke (width 0.05) (type solid)) (fill none) (layer "F.CrtYd"))
    (fp_rect (start -0.499 -0.249) (end 0.499 0.249)
      (stroke (width 0.15) (type solid)) (fill none) (layer "F.Fab"))
    (pad "1" smd roundrect (at -0.484 0 90) (size 0.59 0.64) (layers "F.Cu" "F.Paste" "F.Mask") (roundrect_rratio 0.25)
      (net 57 "/USB/GTR_DP2_C2M_N") (pintype "passive"))
    (pad "2" smd roundrect (at 0.484 0 90) (size 0.59 0.64) (layers "F.Cu" "F.Paste" "F.Mask") (roundrect_rratio 0.25)
      (net 53 "/USB/GTR_DP2_C2M_C_N") (pintype "passive"))
  )
	(footprint "kria-k26-devboard-footprints:C_0402_1005Metric" (layer "F.Cu")
    (at 129.95 78.8)
    (descr "Capacitor SMD 0402")
    (tags "capacitor SMD 0402")
    (property "Author" "Antmicro")
    (property "Dielectric" "X5R")
    (property "License" "Apache-2.0")
    (property "MPN" "GRM155R61H104KE14D")
    (property "Manufacturer" "Murata")
    (property "Sheetfile" "usb.kicad_sch")
    (property "Sheetname" "USB")
    (property "Val" "100n")
    (property "Voltage" "50V")
    (property "ki_description" " ")
    (attr smd)
    (fp_text reference "C46" (at 0.84 0.37) (layer "F.SilkS")
        (effects (font (size 0.7 0.7) (thickness 0.15)) (justify left bottom))
    )
    (fp_text value "C_100n_0402" (at 0 1.4) (layer "F.Fab") hide
        (effects (font (size 0.7 0.7) (thickness 0.15)) (justify left bottom))
    )
    (fp_text user "${REFERENCE}" (at -0.932 3.168) (layer "F.Fab") hide
        (effects (font (size 0.7 0.7) (thickness 0.15)) (justify left bottom))
    )
    (fp_text user "License: Apache-2.0" (at -0.932 5.17) (layer "F.Fab") hide
        (effects (font (size 0.7 0.7) (thickness 0.15)) (justify left bottom))
    )
    (fp_text user "Author: Antmicro" (at -0.932 4.17) (layer "F.Fab") hide
        (effects (font (size 0.7 0.7) (thickness 0.15)) (justify left bottom))
    )
    (fp_rect (start -0.94 -0.47) (end 0.94 0.47)
      (stroke (width 0.05) (type solid)) (fill none) (layer "F.CrtYd"))
    (fp_rect (start -0.499 -0.249) (end 0.499 0.249)
      (stroke (width 0.15) (type solid)) (fill none) (layer "F.Fab"))
    (pad "1" smd roundrect (at -0.484 0) (size 0.59 0.64) (layers "F.Cu" "F.Paste" "F.Mask") (roundrect_rratio 0.25)
      (net 15 "PS_3V3") (pintype "passive"))
    (pad "2" smd roundrect (at 0.484 0) (size 0.59 0.64) (layers "F.Cu" "F.Paste" "F.Mask") (roundrect_rratio 0.25)
      (net 1 "GND") (pintype "passive"))
  )
	(footprint "kria-k26-devboard-footprints:C_0402_1005Metric" (layer "F.Cu")
    (at 122.701223 92.91 90)
    (descr "Capacitor SMD 0402")
    (tags "capacitor SMD 0402")
    (property "Author" "Antmicro")
    (property "Dielectric" "X5R")
    (property "License" "Apache-2.0")
    (property "MPN" "GRM155R61H104KE14D")
    (property "Manufacturer" "Murata")
    (property "Sheetfile" "usb.kicad_sch")
    (property "Sheetname" "USB")
    (property "Val" "100n")
    (property "Voltage" "50V")
    (property "ki_description" " ")
    (attr smd)
    (fp_text reference "C52" (at -1.94 -3.25 90) (layer "F.SilkS")
        (effects (font (size 0.7 0.7) (thickness 0.15)) (justify left bottom))
    )
    (fp_text value "C_100n_0402" (at 0 1.4 90) (layer "F.Fab") hide
        (effects (font (size 0.7 0.7) (thickness 0.15)) (justify left bottom))
    )
    (fp_text user "License: Apache-2.0" (at -0.932 5.17 90) (layer "F.Fab") hide
        (effects (font (size 0.7 0.7) (thickness 0.15)) (justify left bottom))
    )
    (fp_text user "Author: Antmicro" (at -0.932 4.17 90) (layer "F.Fab") hide
        (effects (font (size 0.7 0.7) (thickness 0.15)) (justify left bottom))
    )
    (fp_text user "${REFERENCE}" (at -0.932 3.168 90) (layer "F.Fab") hide
        (effects (font (size 0.7 0.7) (thickness 0.15)) (justify left bottom))
    )
    (fp_rect (start -0.94 -0.47) (end 0.94 0.47)
      (stroke (width 0.05) (type solid)) (fill none) (layer "F.CrtYd"))
    (fp_rect (start -0.499 -0.249) (end 0.499 0.249)
      (stroke (width 0.15) (type solid)) (fill none) (layer "F.Fab"))
    (pad "1" smd roundrect (at -0.484 0 90) (size 0.59 0.64) (layers "F.Cu" "F.Paste" "F.Mask") (roundrect_rratio 0.25)
      (net 56 "/USB/GTR_DP2_C2M_P") (pintype "passive"))
    (pad "2" smd roundrect (at 0.484 0 90) (size 0.59 0.64) (layers "F.Cu" "F.Paste" "F.Mask") (roundrect_rratio 0.25)
      (net 52 "/USB/GTR_DP2_C2M_C_P") (pintype "passive"))
  )
)
